(kicad_pcb
	(version 20260206)
	(generator "pcbnew")
	(generator_version "10.0")
	(general
		(thickness 1.6)
		(legacy_teardrops no)
	)
	(paper "A4")
	(title_block
		(title "01162023_DA0F0TEBIF0_F0T_Expander_BD_F_brd_V02_OCP.brd")
		(comment 1 "Grand Teton / footprints 1678-1683 of 9728")
	)
	(layers
		(0 "F.Cu" signal "TOP")
		(4 "In1.Cu" signal "GND")
		(6 "In2.Cu" signal "VCC")
		(8 "In3.Cu" signal "VCC1")
		(10 "In4.Cu" signal "GND1")
		(12 "In5.Cu" signal "IN1")
		(14 "In6.Cu" signal "GND2")
		(16 "In7.Cu" signal "IN2")
		(18 "In8.Cu" signal "GND3")
		(20 "In9.Cu" signal "IN3")
		(22 "In10.Cu" signal "GND4")
		(24 "In11.Cu" signal "IN4")
		(26 "In12.Cu" signal "GND5")
		(28 "In13.Cu" signal "IN5")
		(30 "In14.Cu" signal "GND6")
		(32 "In15.Cu" signal "IN6")
		(34 "In16.Cu" signal "GND7")
		(2 "B.Cu" signal "BOTTOM")
		(9 "F.Adhes" user "F.Adhesive")
		(11 "B.Adhes" user "B.Adhesive")
		(13 "F.Paste" user "Package Geometry/Pastemask Top")
		(15 "B.Paste" user "Package Geometry/Pastemask Bottom")
		(5 "F.SilkS" user "Ref Des/Silkscreen Top")
		(7 "B.SilkS" user "Ref Des/Silkscreen Bottom")
		(1 "F.Mask" user "Board Geometry/Soldermask Top")
		(3 "B.Mask" user "Board Geometry/Soldermask Bottom")
		(17 "Dwgs.User" user "User.Drawings")
		(19 "Cmts.User" user "User.Comments")
		(21 "Eco1.User" user "User.Eco1")
		(23 "Eco2.User" user "User.Eco2")
		(25 "Edge.Cuts" user "Board Geometry/Outline")
		(27 "Margin" user)
		(31 "F.CrtYd" user "Package Geometry/Place Bound Top")
		(29 "B.CrtYd" user "Package Geometry/Place Bound Bottom")
		(35 "F.Fab" user "Ref Des/Assembly Top")
		(33 "B.Fab" user "Ref Des/Assembly Bottom")
	)
	(footprint ""
		(layer "F.Cu")
		(at 359.156 -188.214)
		(property "Reference" "R4606"
			(at 0 0 0)
			(layer "F.SilkS")
			(hide yes)
			(effects
				(font
					(size 1.27 1.27)
				)
			)
		)
		(property "Value" ""
			(at 0 0 0)
			(layer "F.Fab")
			(effects
				(font
					(size 1.27 1.27)
				)
			)
		)
		(duplicate_pad_numbers_are_jumpers no)
		(fp_line
			(start -0.7874 -0.4064)
			(end 0.7874 -0.4064)
			(stroke
				(width 0.1524)
				(type default)
			)
			(layer "F.SilkS")
		)
		(fp_line
			(start -0.7874 0.4064)
			(end -0.7874 -0.4064)
			(stroke
				(width 0.1524)
				(type default)
			)
			(layer "F.SilkS")
		)
		(fp_line
			(start 0.7874 -0.4064)
			(end 0.7874 0.4064)
			(stroke
				(width 0.1524)
				(type default)
			)
			(layer "F.SilkS")
		)
		(fp_line
			(start 0.7874 0.4064)
			(end -0.7874 0.4064)
			(stroke
				(width 0.1524)
				(type default)
			)
			(layer "F.SilkS")
		)
		(fp_line
			(start -0.67945 -0.305054)
			(end -0.12065 -0.305054)
			(stroke
				(width 0.1)
				(type default)
			)
			(layer "F.Fab")
		)
		(fp_line
			(start -0.67945 0.3048)
			(end -0.67945 -0.305054)
			(stroke
				(width 0.1)
				(type default)
			)
			(layer "F.Fab")
		)
		(fp_line
			(start -0.12065 -0.305054)
			(end -0.12065 -0.2794)
			(stroke
				(width 0.1)
				(type default)
			)
			(layer "F.Fab")
		)
		(fp_line
			(start -0.12065 -0.2794)
			(end 0.12065 -0.2794)
			(stroke
				(width 0.1)
				(type default)
			)
			(layer "F.Fab")
		)
		(fp_line
			(start -0.12065 0.2794)
			(end -0.12065 0.3048)
			(stroke
				(width 0.1)
				(type default)
			)
			(layer "F.Fab")
		)
		(fp_line
			(start -0.12065 0.3048)
			(end -0.67945 0.3048)
			(stroke
				(width 0.1)
				(type default)
			)
			(layer "F.Fab")
		)
		(fp_line
			(start 0.120396 0.2794)
			(end -0.12065 0.2794)
			(stroke
				(width 0.1)
				(type default)
			)
			(layer "F.Fab")
		)
		(fp_line
			(start 0.120396 0.3048)
			(end 0.120396 0.2794)
			(stroke
				(width 0.1)
				(type default)
			)
			(layer "F.Fab")
		)
		(fp_line
			(start 0.12065 -0.3048)
			(end 0.67945 -0.3048)
			(stroke
				(width 0.1)
				(type default)
			)
			(layer "F.Fab")
		)
		(fp_line
			(start 0.12065 -0.2794)
			(end 0.12065 -0.3048)
			(stroke
				(width 0.1)
				(type default)
			)
			(layer "F.Fab")
		)
		(fp_line
			(start 0.67945 -0.3048)
			(end 0.67945 0.3048)
			(stroke
				(width 0.1)
				(type default)
			)
			(layer "F.Fab")
		)
		(fp_line
			(start 0.67945 0.3048)
			(end 0.120396 0.3048)
			(stroke
				(width 0.1)
				(type default)
			)
			(layer "F.Fab")
		)
		(pad "1" smd circle
			(at -0.40005 0)
			(size 0 0)
			(layers "F.Cu" "F.Mask" "F.Paste")
			(net "P3V3_AUX")
		)
		(pad "2" smd circle
			(at 0.40005 0)
			(size 0 0)
			(layers "F.Cu" "F.Mask" "F.Paste")
			(net "RST_PEX_SSD2_PERST_R_N")
		)
	)
	(footprint ""
		(layer "F.Cu")
		(at 447.173858 -103.668068)
		(property "Reference" "PC825"
			(at 0 0 0)
			(layer "F.SilkS")
			(hide yes)
			(effects
				(font
					(size 1.27 1.27)
				)
			)
		)
		(property "Value" ""
			(at 0 0 0)
			(layer "F.Fab")
			(effects
				(font
					(size 1.27 1.27)
				)
			)
		)
		(duplicate_pad_numbers_are_jumpers no)
		(fp_line
			(start -1.524 -0.762)
			(end 1.524 -0.762)
			(stroke
				(width 0.1524)
				(type default)
			)
			(layer "F.SilkS")
		)
		(fp_line
			(start -1.524 0.762)
			(end -1.524 -0.762)
			(stroke
				(width 0.1524)
				(type default)
			)
			(layer "F.SilkS")
		)
		(fp_line
			(start 1.524 -0.762)
			(end 1.524 0.762)
			(stroke
				(width 0.1524)
				(type default)
			)
			(layer "F.SilkS")
		)
		(fp_line
			(start 1.524 0.762)
			(end -1.524 0.762)
			(stroke
				(width 0.1524)
				(type default)
			)
			(layer "F.SilkS")
		)
		(fp_line
			(start -1.1049 -0.724916)
			(end -1.1049 0.724916)
			(stroke
				(width 0.1)
				(type default)
			)
			(layer "F.Fab")
		)
		(fp_line
			(start -1.1049 0.724916)
			(end 1.1049 0.724916)
			(stroke
				(width 0.1)
				(type default)
			)
			(layer "F.Fab")
		)
		(fp_line
			(start 1.1049 -0.724916)
			(end -1.1049 -0.724916)
			(stroke
				(width 0.1)
				(type default)
			)
			(layer "F.Fab")
		)
		(fp_line
			(start 1.1049 0.724916)
			(end 1.1049 -0.724916)
			(stroke
				(width 0.1)
				(type default)
			)
			(layer "F.Fab")
		)
		(pad "1" smd rect
			(at -0.889 0 180)
			(size 1.016 1.27)
			(layers "F.Cu" "F.Mask" "F.Paste")
			(net "P12V_NIC7_R")
		)
		(pad "2" smd rect
			(at 0.889 0 180)
			(size 1.016 1.27)
			(layers "F.Cu" "F.Mask" "F.Paste")
			(net "GND")
		)
	)
	(footprint ""
		(layer "F.Cu")
		(at 114.945668 -356.244906 90)
		(property "Reference" "C360"
			(at 0 0 90)
			(layer "F.SilkS")
			(hide yes)
			(effects
				(font
					(size 1.27 1.27)
				)
			)
		)
		(property "Value" ""
			(at 0 0 90)
			(layer "F.Fab")
			(effects
				(font
					(size 1.27 1.27)
				)
			)
		)
		(duplicate_pad_numbers_are_jumpers no)
		(fp_line
			(start 0.299974 -0.150114)
			(end 0.299974 0.150114)
			(stroke
				(width 0.1)
				(type default)
			)
			(layer "F.Fab")
		)
		(fp_line
			(start -0.299974 -0.150114)
			(end 0.299974 -0.150114)
			(stroke
				(width 0.1)
				(type default)
			)
			(layer "F.Fab")
		)
		(fp_line
			(start 0.299974 0.150114)
			(end -0.299974 0.150114)
			(stroke
				(width 0.1)
				(type default)
			)
			(layer "F.Fab")
		)
		(fp_line
			(start -0.299974 0.150114)
			(end -0.299974 -0.150114)
			(stroke
				(width 0.1)
				(type default)
			)
			(layer "F.Fab")
		)
		(pad "1" smd rect
			(at -0.2667 0 90)
			(size 0.3048 0.381)
			(layers "F.Cu" "F.Mask" "F.Paste")
			(net "P5E_PEX1_STN6_TX_DP<101>")
		)
		(pad "2" smd rect
			(at 0.2667 0 90)
			(size 0.3048 0.381)
			(layers "F.Cu" "F.Mask" "F.Paste")
			(net "P5E_PEX1_STN6_TX_C_DP<101>")
		)
	)
	(footprint ""
		(layer "F.Cu")
		(at 124.808742 -166.674038 90)
		(property "Reference" "C4451"
			(at 0 0 90)
			(layer "F.SilkS")
			(hide yes)
			(effects
				(font
					(size 1.27 1.27)
				)
			)
		)
		(property "Value" ""
			(at 0 0 90)
			(layer "F.Fab")
			(effects
				(font
					(size 1.27 1.27)
				)
			)
		)
		(duplicate_pad_numbers_are_jumpers no)
		(fp_line
			(start 0.7874 -0.4064)
			(end 0.7874 0.4064)
			(stroke
				(width 0.1524)
				(type default)
			)
			(layer "F.SilkS")
		)
		(fp_line
			(start -0.7874 -0.4064)
			(end 0.7874 -0.4064)
			(stroke
				(width 0.1524)
				(type default)
			)
			(layer "F.SilkS")
		)
		(fp_line
			(start 0.7874 0.4064)
			(end -0.7874 0.4064)
			(stroke
				(width 0.1524)
				(type default)
			)
			(layer "F.SilkS")
		)
		(fp_line
			(start -0.7874 0.4064)
			(end -0.7874 -0.4064)
			(stroke
				(width 0.1524)
				(type default)
			)
			(layer "F.SilkS")
		)
		(fp_line
			(start -0.12065 -0.305054)
			(end -0.12065 -0.2794)
			(stroke
				(width 0.1)
				(type default)
			)
			(layer "F.Fab")
		)
		(fp_line
			(start -0.67945 -0.305054)
			(end -0.12065 -0.305054)
			(stroke
				(width 0.1)
				(type default)
			)
			(layer "F.Fab")
		)
		(fp_line
			(start 0.67945 -0.3048)
			(end 0.67945 0.3048)
			(stroke
				(width 0.1)
				(type default)
			)
			(layer "F.Fab")
		)
		(fp_line
			(start 0.12065 -0.3048)
			(end 0.67945 -0.3048)
			(stroke
				(width 0.1)
				(type default)
			)
			(layer "F.Fab")
		)
		(fp_line
			(start 0.12065 -0.2794)
			(end 0.12065 -0.3048)
			(stroke
				(width 0.1)
				(type default)
			)
			(layer "F.Fab")
		)
		(fp_line
			(start -0.12065 -0.2794)
			(end 0.12065 -0.2794)
			(stroke
				(width 0.1)
				(type default)
			)
			(layer "F.Fab")
		)
		(fp_line
			(start 0.120396 0.2794)
			(end -0.12065 0.2794)
			(stroke
				(width 0.1)
				(type default)
			)
			(layer "F.Fab")
		)
		(fp_line
			(start -0.12065 0.2794)
			(end -0.12065 0.3048)
			(stroke
				(width 0.1)
				(type default)
			)
			(layer "F.Fab")
		)
		(fp_line
			(start 0.67945 0.3048)
			(end 0.120396 0.3048)
			(stroke
				(width 0.1)
				(type default)
			)
			(layer "F.Fab")
		)
		(fp_line
			(start 0.120396 0.3048)
			(end 0.120396 0.2794)
			(stroke
				(width 0.1)
				(type default)
			)
			(layer "F.Fab")
		)
		(fp_line
			(start -0.12065 0.3048)
			(end -0.67945 0.3048)
			(stroke
				(width 0.1)
				(type default)
			)
			(layer "F.Fab")
		)
		(fp_line
			(start -0.67945 0.3048)
			(end -0.67945 -0.305054)
			(stroke
				(width 0.1)
				(type default)
			)
			(layer "F.Fab")
		)
		(pad "1" smd circle
			(at -0.40005 0 90)
			(size 0 0)
			(layers "F.Cu" "F.Mask" "F.Paste")
			(net "GND")
		)
		(pad "2" smd circle
			(at 0.40005 0 90)
			(size 0 0)
			(layers "F.Cu" "F.Mask" "F.Paste")
			(net "P3V3_AUX")
		)
	)
	(footprint ""
		(layer "F.Cu")
		(at 100.845874 -46.4439 180)
		(property "Reference" "U56"
			(at -0.042926 -2.35077 0)
			(unlocked yes)
			(layer "F.SilkS")
			(effects
				(font
					(size 0.7874 0.5842)
					(thickness 0.1524)
				)
			)
		)
		(property "Value" ""
			(at 0 0 180)
			(layer "F.Fab")
			(effects
				(font
					(size 1.27 1.27)
				)
			)
		)
		(duplicate_pad_numbers_are_jumpers no)
		(fp_line
			(start 1.500124 1.500124)
			(end 1.004062 1.500124)
			(stroke
				(width 0.1524)
				(type default)
			)
			(layer "F.SilkS")
		)
		(fp_line
			(start 1.500124 1.004062)
			(end 1.500124 1.500124)
			(stroke
				(width 0.1524)
				(type default)
			)
			(layer "F.SilkS")
		)
		(fp_line
			(start 1.500124 -1.500124)
			(end 1.500124 -1.004062)
			(stroke
				(width 0.1524)
				(type default)
			)
			(layer "F.SilkS")
		)
		(fp_line
			(start 1.004062 -1.500124)
			(end 1.500124 -1.500124)
			(stroke
				(width 0.1524)
				(type default)
			)
			(layer "F.SilkS")
		)
		(fp_line
			(start -1.004062 1.500124)
			(end -1.500124 1.500124)
			(stroke
				(width 0.1524)
				(type default)
			)
			(layer "F.SilkS")
		)
		(fp_line
			(start -1.500124 1.500124)
			(end -1.500124 1.004062)
			(stroke
				(width 0.1524)
				(type default)
			)
			(layer "F.SilkS")
		)
		(fp_line
			(start -1.500124 -1.004062)
			(end -1.500124 -1.500124)
			(stroke
				(width 0.1524)
				(type default)
			)
			(layer "F.SilkS")
		)
		(fp_line
			(start -1.500124 -1.500124)
			(end -1.004062 -1.500124)
			(stroke
				(width 0.1524)
				(type default)
			)
			(layer "F.SilkS")
		)
		(fp_poly
			(pts
				(xy -1.947926 -2.04216) (xy -2.666238 -1.323848) (xy -1.588516 -0.964438)
			)
			(stroke
				(width 0)
				(type default)
			)
			(fill yes)
			(layer "F.SilkS")
		)
		(fp_line
			(start 1.500124 1.500124)
			(end -1.500124 1.500124)
			(stroke
				(width 0.1)
				(type default)
			)
			(layer "F.Fab")
		)
		(fp_line
			(start 1.500124 -1.500124)
			(end 1.500124 1.500124)
			(stroke
				(width 0.1)
				(type default)
			)
			(layer "F.Fab")
		)
		(fp_line
			(start -1.500124 1.500124)
			(end -1.500124 -1.500124)
			(stroke
				(width 0.1)
				(type default)
			)
			(layer "F.Fab")
		)
		(fp_line
			(start -1.500124 -1.500124)
			(end 1.500124 -1.500124)
			(stroke
				(width 0.1)
				(type default)
			)
			(layer "F.Fab")
		)
		(fp_poly
			(pts
				(xy -2.847848 -1.258062) (xy -2.847848 -0.242062) (xy -1.831848 -0.750062)
			)
			(stroke
				(width 0)
				(type default)
			)
			(fill yes)
			(layer "F.Fab")
		)
		(pad "1" smd rect
			(at -1.400048 -0.750062 90)
			(size 0.2286 0.6096)
			(layers "F.Cu" "F.Mask" "F.Paste")
			(net "SSD3_ADC_A1")
		)
		(pad "2" smd rect
			(at -1.400048 -0.249936 90)
			(size 0.2286 0.6096)
			(layers "F.Cu" "F.Mask" "F.Paste")
			(net "SSD3_ADC_A0")
		)
		(pad "3" smd rect
			(at -1.400048 0.249936 90)
			(size 0.2286 0.6096)
			(layers "F.Cu" "F.Mask" "F.Paste")
			(net "SSD3_ADC_ALERT_N")
		)
		(pad "4" smd rect
			(at -1.400048 0.750062 90)
			(size 0.2286 0.6096)
			(layers "F.Cu" "F.Mask" "F.Paste")
			(net "SMB_SSD3_ADC_SDA")
		)
		(pad "5" smd rect
			(at -0.750062 1.400048 180)
			(size 0.2286 0.6096)
			(layers "F.Cu" "F.Mask" "F.Paste")
			(net "SMB_SSD3_ADC_SCL")
		)
		(pad "6" smd rect
			(at -0.249936 1.400048 180)
			(size 0.2286 0.6096)
			(layers "F.Cu" "F.Mask" "F.Paste")
			(net "Net_8744")
		)
		(pad "7" smd rect
			(at 0.249936 1.400048 180)
			(size 0.2286 0.6096)
			(layers "F.Cu" "F.Mask" "F.Paste")
			(net "Net_8743")
		)
		(pad "8" smd rect
			(at 0.750062 1.400048 180)
			(size 0.2286 0.6096)
			(layers "F.Cu" "F.Mask" "F.Paste")
			(net "Net_8742")
		)
		(pad "9" smd rect
			(at 1.400048 0.750062 90)
			(size 0.2286 0.6096)
			(layers "F.Cu" "F.Mask" "F.Paste")
			(net "P3V3_AUX")
		)
		(pad "10" smd rect
			(at 1.400048 0.249936 90)
			(size 0.2286 0.6096)
			(layers "F.Cu" "F.Mask" "F.Paste")
			(net "GND")
		)
		(pad "11" smd rect
			(at 1.400048 -0.249936 90)
			(size 0.2286 0.6096)
			(layers "F.Cu" "F.Mask" "F.Paste")
			(net "P12V_SSD3_R")
		)
		(pad "12" smd rect
			(at 1.400048 -0.750062 90)
			(size 0.2286 0.6096)
			(layers "F.Cu" "F.Mask" "F.Paste")
			(net "P12V_SSD3_VIN_N")
		)
		(pad "13" smd rect
			(at 0.750062 -1.400048 180)
			(size 0.2286 0.6096)
			(layers "F.Cu" "F.Mask" "F.Paste")
			(net "P12V_SSD3_VIN_P")
		)
		(pad "14" smd rect
			(at 0.249936 -1.400048 180)
			(size 0.2286 0.6096)
			(layers "F.Cu" "F.Mask" "F.Paste")
			(net "Net_8741")
		)
		(pad "15" smd rect
			(at -0.249936 -1.400048 180)
			(size 0.2286 0.6096)
			(layers "F.Cu" "F.Mask" "F.Paste")
			(net "Net_8740")
		)
		(pad "16" smd rect
			(at -0.750062 -1.400048 180)
			(size 0.2286 0.6096)
			(layers "F.Cu" "F.Mask" "F.Paste")
			(net "Net_8739")
		)
		(pad "TH" smd rect
			(at 0 0 180)
			(size 1.7018 1.7018)
			(layers "F.Cu" "F.Mask" "F.Paste")
			(net "GND")
		)
		(zone
			(layer "F.Cu")
			(hatch none 0.5)
			(connect_pads
				(clearance 0)
			)
			(min_thickness 0.25)
			(keepout
				(tracks not_allowed)
				(vias allowed)
				(pads allowed)
				(copperpour not_allowed)
				(footprints allowed)
			)
			(placement
				(enabled no)
				(sheetname "")
			)
			(fill
				(thermal_gap 0.5)
				(thermal_bridge_width 0.5)
				(island_removal_mode 0)
			)
			(polygon
				(pts
					(xy 101.890322 -46.4185) (xy 101.890322 -45.399452) (xy 99.801426 -45.399452) (xy 99.801426 -47.488348)
					(xy 101.890322 -47.488348) (xy 101.890322 -46.4439) (xy 101.747574 -46.4439) (xy 101.747574 -47.3456)
					(xy 99.944174 -47.3456) (xy 99.944174 -45.5422) (xy 101.747574 -45.5422) (xy 101.747574 -46.4185)
				)
			)
		)
	)
	(footprint ""
		(layer "F.Cu")
		(at 334.602582 -284.834838 90)
		(property "Reference" "PC139"
			(at 0 0 90)
			(layer "F.SilkS")
			(hide yes)
			(effects
				(font
					(size 1.27 1.27)
				)
			)
		)
		(property "Value" ""
			(at 0 0 90)
			(layer "F.Fab")
			(effects
				(font
					(size 1.27 1.27)
				)
			)
		)
		(duplicate_pad_numbers_are_jumpers no)
		(fp_line
			(start 0.7874 -0.4064)
			(end 0.7874 0.4064)
			(stroke
				(width 0.1524)
				(type default)
			)
			(layer "F.SilkS")
		)
		(fp_line
			(start -0.7874 -0.4064)
			(end 0.7874 -0.4064)
			(stroke
				(width 0.1524)
				(type default)
			)
			(layer "F.SilkS")
		)
		(fp_line
			(start 0.7874 0.4064)
			(end -0.7874 0.4064)
			(stroke
				(width 0.1524)
				(type default)
			)
			(layer "F.SilkS")
		)
		(fp_line
			(start -0.7874 0.4064)
			(end -0.7874 -0.4064)
			(stroke
				(width 0.1524)
				(type default)
			)
			(layer "F.SilkS")
		)
		(fp_line
			(start -0.12065 -0.305054)
			(end -0.12065 -0.2794)
			(stroke
				(width 0.1)
				(type default)
			)
			(layer "F.Fab")
		)
		(fp_line
			(start -0.67945 -0.305054)
			(end -0.12065 -0.305054)
			(stroke
				(width 0.1)
				(type default)
			)
			(layer "F.Fab")
		)
		(fp_line
			(start 0.67945 -0.3048)
			(end 0.67945 0.3048)
			(stroke
				(width 0.1)
				(type default)
			)
			(layer "F.Fab")
		)
		(fp_line
			(start 0.12065 -0.3048)
			(end 0.67945 -0.3048)
			(stroke
				(width 0.1)
				(type default)
			)
			(layer "F.Fab")
		)
		(fp_line
			(start 0.12065 -0.2794)
			(end 0.12065 -0.3048)
			(stroke
				(width 0.1)
				(type default)
			)
			(layer "F.Fab")
		)
		(fp_line
			(start -0.12065 -0.2794)
			(end 0.12065 -0.2794)
			(stroke
				(width 0.1)
				(type default)
			)
			(layer "F.Fab")
		)
		(fp_line
			(start 0.120396 0.2794)
			(end -0.12065 0.2794)
			(stroke
				(width 0.1)
				(type default)
			)
			(layer "F.Fab")
		)
		(fp_line
			(start -0.12065 0.2794)
			(end -0.12065 0.3048)
			(stroke
				(width 0.1)
				(type default)
			)
			(layer "F.Fab")
		)
		(fp_line
			(start 0.67945 0.3048)
			(end 0.120396 0.3048)
			(stroke
				(width 0.1)
				(type default)
			)
			(layer "F.Fab")
		)
		(fp_line
			(start 0.120396 0.3048)
			(end 0.120396 0.2794)
			(stroke
				(width 0.1)
				(type default)
			)
			(layer "F.Fab")
		)
		(fp_line
			(start -0.12065 0.3048)
			(end -0.67945 0.3048)
			(stroke
				(width 0.1)
				(type default)
			)
			(layer "F.Fab")
		)
		(fp_line
			(start -0.67945 0.3048)
			(end -0.67945 -0.305054)
			(stroke
				(width 0.1)
				(type default)
			)
			(layer "F.Fab")
		)
		(pad "1" smd circle
			(at -0.40005 0 90)
			(size 0 0)
			(layers "F.Cu" "F.Mask" "F.Paste")
			(net "SW_P12V_P0V8_PEX2_FLT")
		)
		(pad "2" smd circle
			(at 0.40005 0 90)
			(size 0 0)
			(layers "F.Cu" "F.Mask" "F.Paste")
			(net "GND")
		)
	)
)
